# T6G (Grand Teton) — schematic netlist excerpt (pin names and nets, part order shuffled) for the footprints in the layout excerpt that follows; sources: Cadence DE-HDL packaged netlist, KiCad conversion of 04192023_DAF0TMB3IC0_F0TG_MB_C_brd_V02_OCP.brd

PU287  MP5991GLUZ  MP5991GLU-Z IC  pkg LGA32_TH_0-5_5X5  page 263
  VOUT1  = P12V_AUX
  VOUT2  = P12V_AUX
  D_OC  = HSC_D_OC_1
  \on\  = HSC_ON
  GOK  = HSC_FAULT
  FLT_TYPE  = HSC_FLT_TYPE_1
  NC1  = HSC_NC1_1
  MODE  = HSC_MODE_1
  VIN1  = P12V_PSU
  VIN2  = P12V_PSU
  VIN3  = P12V_PSU
  VIN4  = P12V_PSU
  VIN5  = P12V_PSU
  VIN6  = P12V_PSU
  VIN7  = P12V_PSU
  VIN8  = P12V_PSU
  SCREF_OCWREF  = HSC_SCREF_1
  VTEMP  = HSC_VTEMP
  SS  = HSC_SS
  GND  = AGND_HSC
  VDD33  = HSC_VDD_R_1
  IMON  = HSC_IMON
  CS  = HSC_CS_1
  OCREF  = HSC_OCREF
  VOUT3  = P12V_AUX
  VOUT4  = P12V_AUX
  VOUT5  = P12V_AUX
  VOUT6  = P12V_AUX
  VOUT7  = P12V_AUX
  VOUT8  = P12V_AUX
  VOUT9  = P12V_AUX
  VOUT10  = P12V_AUX
  VIN9  = P12V_PSU

(kicad_pcb
	(version 20260206)
	(generator "pcbnew")
	(generator_version "10.0")
	(general
		(thickness 1.6)
		(legacy_teardrops no)
	)
	(paper "A4")
	(title_block
		(title "04192023_DAF0TMB3IC0_F0TG_MB_C_brd_V02_OCP.brd")
		(comment 1 "Grand Teton / footprints 3760-3760 of 8354")
	)
	(layers
		(0 "F.Cu" signal "TOP")
		(4 "In1.Cu" signal "GND")
		(6 "In2.Cu" signal "IN1")
		(8 "In3.Cu" signal "GND1")
		(10 "In4.Cu" signal "IN2")
		(12 "In5.Cu" signal "GND2")
		(14 "In6.Cu" signal "IN3")
		(16 "In7.Cu" signal "GND3")
		(18 "In8.Cu" signal "VCC")
		(20 "In9.Cu" signal "VCC1")
		(22 "In10.Cu" signal "GND4")
		(24 "In11.Cu" signal "IN4")
		(26 "In12.Cu" signal "GND5")
		(28 "In13.Cu" signal "IN5")
		(30 "In14.Cu" signal "GND6")
		(32 "In15.Cu" signal "IN6")
		(34 "In16.Cu" signal "GND7")
		(2 "B.Cu" signal "BOTTOM")
		(9 "F.Adhes" user "F.Adhesive")
		(11 "B.Adhes" user "B.Adhesive")
		(13 "F.Paste" user "Package Geometry/Pastemask Top")
		(15 "B.Paste" user "Package Geometry/Pastemask Bottom")
		(5 "F.SilkS" user "Ref Des/Silkscreen Top")
		(7 "B.SilkS" user "Ref Des/Silkscreen Bottom")
		(1 "F.Mask" user "Board Geometry/Soldermask Top")
		(3 "B.Mask" user "Board Geometry/Soldermask Bottom")
		(17 "Dwgs.User" user "User.Drawings")
		(19 "Cmts.User" user "User.Comments")
		(21 "Eco1.User" user "User.Eco1")
		(23 "Eco2.User" user "User.Eco2")
		(25 "Edge.Cuts" user "Board Geometry/Outline")
		(27 "Margin" user)
		(31 "F.CrtYd" user "Package Geometry/Place Bound Top")
		(29 "B.CrtYd" user "Package Geometry/Place Bound Bottom")
		(35 "F.Fab" user "Ref Des/Assembly Top")
		(33 "B.Fab" user "Ref Des/Assembly Bottom")
	)
	(footprint ""
		(layer "F.Cu")
		(at 199.536558 -401.920202 180)
		(property "Reference" "PU287"
			(at 3.001772 -4.951222 90)
			(unlocked yes)
			(layer "F.SilkS")
			(effects
				(font
					(size 0.7874 0.5842)
					(thickness 0.1524)
				)
			)
		)
		(property "Value" ""
			(at 0 0 180)
			(layer "F.Fab")
			(effects
				(font
					(size 1.27 1.27)
				)
			)
		)
		(duplicate_pad_numbers_are_jumpers no)
		(fp_line
			(start 2.567686 2.567686)
			(end 2.567686 -2.567686)
			(stroke
				(width 0.1524)
				(type default)
			)
			(layer "F.SilkS")
		)
		(fp_line
			(start 2.567686 -2.567686)
			(end -2.567686 -2.567686)
			(stroke
				(width 0.1524)
				(type default)
			)
			(layer "F.SilkS")
		)
		(fp_line
			(start -2.567686 2.567686)
			(end 2.567686 2.567686)
			(stroke
				(width 0.1524)
				(type default)
			)
			(layer "F.SilkS")
		)
		(fp_line
			(start -2.567686 -2.567686)
			(end -2.567686 2.567686)
			(stroke
				(width 0.1524)
				(type default)
			)
			(layer "F.SilkS")
		)
		(fp_poly
			(pts
				(xy -2.632456 -2.13233) (xy -3.709924 -2.491486) (xy -2.991612 -3.209798)
			)
			(stroke
				(width 0)
				(type default)
			)
			(fill yes)
			(layer "F.SilkS")
		)
		(fp_line
			(start 2.549906 2.549906)
			(end 2.549906 -2.549906)
			(stroke
				(width 0.1)
				(type default)
			)
			(layer "F.Fab")
		)
		(fp_line
			(start 2.549906 -2.549906)
			(end -2.549906 -2.549906)
			(stroke
				(width 0.1)
				(type default)
			)
			(layer "F.Fab")
		)
		(fp_line
			(start -2.549906 2.549906)
			(end 2.549906 2.549906)
			(stroke
				(width 0.1)
				(type default)
			)
			(layer "F.Fab")
		)
		(fp_line
			(start -2.549906 -2.549906)
			(end -2.549906 2.549906)
			(stroke
				(width 0.1)
				(type default)
			)
			(layer "F.Fab")
		)
		(fp_poly
			(pts
				(xy -3.806698 -2.25806) (xy -3.806698 -1.24206) (xy -2.790698 -1.75006)
			)
			(stroke
				(width 0)
				(type default)
			)
			(fill yes)
			(layer "F.Fab")
		)
		(pad "1" smd rect
			(at -2.250186 -1.75006 270)
			(size 0.254 0.3556)
			(layers "F.Cu" "F.Mask" "F.Paste")
			(net "P12V_AUX")
		)
		(pad "2" smd rect
			(at -2.237486 -1.249934 270)
			(size 0.254 0.381)
			(layers "F.Cu" "F.Mask" "F.Paste")
			(net "P12V_AUX")
		)
		(pad "3" smd rect
			(at -2.237486 -0.750062 270)
			(size 0.254 0.381)
			(layers "F.Cu" "F.Mask" "F.Paste")
			(net "HSC_D_OC_1")
		)
		(pad "4" smd rect
			(at -2.237486 -0.249936 270)
			(size 0.254 0.381)
			(layers "F.Cu" "F.Mask" "F.Paste")
			(net "HSC_ON")
		)
		(pad "5" smd rect
			(at -2.237486 0.249936 270)
			(size 0.254 0.381)
			(layers "F.Cu" "F.Mask" "F.Paste")
			(net "HSC_FAULT")
		)
		(pad "6" smd rect
			(at -2.237486 0.750062 270)
			(size 0.254 0.381)
			(layers "F.Cu" "F.Mask" "F.Paste")
			(net "HSC_FLT_TYPE_1")
		)
		(pad "7" smd rect
			(at -2.237486 1.249934 270)
			(size 0.254 0.381)
			(layers "F.Cu" "F.Mask" "F.Paste")
			(net "HSC_NC1_1")
		)
		(pad "8" smd rect
			(at -2.250186 1.75006 270)
			(size 0.254 0.3556)
			(layers "F.Cu" "F.Mask" "F.Paste")
			(net "HSC_MODE_1")
		)
		(pad "9" smd rect
			(at -1.75006 2.250186 180)
			(size 0.254 0.3556)
			(layers "F.Cu" "F.Mask" "F.Paste")
			(net "P12V_PSU")
		)
		(pad "10" smd rect
			(at -1.249934 2.237486 180)
			(size 0.254 0.381)
			(layers "F.Cu" "F.Mask" "F.Paste")
			(net "P12V_PSU")
		)
		(pad "11" smd rect
			(at -0.750062 2.237486 180)
			(size 0.254 0.381)
			(layers "F.Cu" "F.Mask" "F.Paste")
			(net "P12V_PSU")
		)
		(pad "12" smd rect
			(at -0.249936 2.237486 180)
			(size 0.254 0.381)
			(layers "F.Cu" "F.Mask" "F.Paste")
			(net "P12V_PSU")
		)
		(pad "13" smd rect
			(at 0.249936 2.237486 180)
			(size 0.254 0.381)
			(layers "F.Cu" "F.Mask" "F.Paste")
			(net "P12V_PSU")
		)
		(pad "14" smd rect
			(at 0.750062 2.237486 180)
			(size 0.254 0.381)
			(layers "F.Cu" "F.Mask" "F.Paste")
			(net "P12V_PSU")
		)
		(pad "15" smd rect
			(at 1.249934 2.237486 180)
			(size 0.254 0.381)
			(layers "F.Cu" "F.Mask" "F.Paste")
			(net "P12V_PSU")
		)
		(pad "16" smd rect
			(at 1.75006 2.250186 180)
			(size 0.254 0.3556)
			(layers "F.Cu" "F.Mask" "F.Paste")
			(net "P12V_PSU")
		)
		(pad "17" smd rect
			(at 2.250186 1.75006 270)
			(size 0.254 0.3556)
			(layers "F.Cu" "F.Mask" "F.Paste")
			(net "HSC_SCREF_1")
		)
		(pad "18" smd rect
			(at 2.237486 1.249934 270)
			(size 0.254 0.381)
			(layers "F.Cu" "F.Mask" "F.Paste")
			(net "HSC_VTEMP")
		)
		(pad "19" smd rect
			(at 2.237486 0.750062 270)
			(size 0.254 0.381)
			(layers "F.Cu" "F.Mask" "F.Paste")
			(net "HSC_SS")
		)
		(pad "20" smd rect
			(at 2.237486 0.249936 270)
			(size 0.254 0.381)
			(layers "F.Cu" "F.Mask" "F.Paste")
			(net "AGND_HSC")
		)
		(pad "21" smd rect
			(at 2.237486 -0.249936 270)
			(size 0.254 0.381)
			(layers "F.Cu" "F.Mask" "F.Paste")
			(net "HSC_VDD_R_1")
		)
		(pad "22" smd rect
			(at 2.237486 -0.750062 270)
			(size 0.254 0.381)
			(layers "F.Cu" "F.Mask" "F.Paste")
			(net "HSC_IMON")
		)
		(pad "23" smd rect
			(at 2.237486 -1.249934 270)
			(size 0.254 0.381)
			(layers "F.Cu" "F.Mask" "F.Paste")
			(net "HSC_CS_1")
		)
		(pad "24" smd rect
			(at 2.250186 -1.75006 270)
			(size 0.254 0.3556)
			(layers "F.Cu" "F.Mask" "F.Paste")
			(net "HSC_OCREF")
		)
		(pad "25" smd rect
			(at 1.75006 -2.250186 180)
			(size 0.254 0.3556)
			(layers "F.Cu" "F.Mask" "F.Paste")
			(net "P12V_AUX")
		)
		(pad "26" smd rect
			(at 1.249934 -2.237486 180)
			(size 0.254 0.381)
			(layers "F.Cu" "F.Mask" "F.Paste")
			(net "P12V_AUX")
		)
		(pad "27" smd rect
			(at 0.750062 -2.237486 180)
			(size 0.254 0.381)
			(layers "F.Cu" "F.Mask" "F.Paste")
			(net "P12V_AUX")
		)
		(pad "28" smd rect
			(at 0.249936 -2.237486 180)
			(size 0.254 0.381)
			(layers "F.Cu" "F.Mask" "F.Paste")
			(net "P12V_AUX")
		)
		(pad "29" smd rect
			(at -0.249936 -2.237486 180)
			(size 0.254 0.381)
			(layers "F.Cu" "F.Mask" "F.Paste")
			(net "P12V_AUX")
		)
		(pad "30" smd rect
			(at -0.750062 -2.237486 180)
			(size 0.254 0.381)
			(layers "F.Cu" "F.Mask" "F.Paste")
			(net "P12V_AUX")
		)
		(pad "31" smd rect
			(at -1.249934 -2.237486 180)
			(size 0.254 0.381)
			(layers "F.Cu" "F.Mask" "F.Paste")
			(net "P12V_AUX")
		)
		(pad "32" smd rect
			(at -1.75006 -2.250186 180)
			(size 0.254 0.3556)
			(layers "F.Cu" "F.Mask" "F.Paste")
			(net "P12V_AUX")
		)
		(pad "33" smd rect
			(at 0 0 180)
			(size 3.4036 3.4036)
			(layers "F.Cu" "F.Mask" "F.Paste")
			(net "P12V_PSU")
		)
		(zone
			(layer "F.Cu")
			(hatch none 0.5)
			(connect_pads
				(clearance 0)
			)
			(min_thickness 0.25)
			(keepout
				(tracks not_allowed)
				(vias allowed)
				(pads allowed)
				(copperpour not_allowed)
				(footprints allowed)
			)
			(placement
				(enabled no)
				(sheetname "")
			)
			(fill
				(thermal_gap 0.5)
				(thermal_bridge_width 0.5)
				(island_removal_mode 0)
			)
			(polygon
				(pts
					(xy 197.514972 -403.61108) (xy 197.783958 -403.61108) (xy 197.783958 -400.167602) (xy 201.289158 -400.167602)
					(xy 201.289158 -402.428202) (xy 201.532744 -402.428202) (xy 201.532744 -400.472402) (xy 201.558144 -400.472402)
					(xy 201.558144 -399.898616) (xy 200.984358 -399.898616) (xy 200.984358 -399.924016) (xy 198.088758 -399.924016)
					(xy 198.088758 -399.898616) (xy 197.514972 -399.898616) (xy 197.514972 -400.472402) (xy 197.540372 -400.472402)
					(xy 197.540372 -403.368002) (xy 197.514972 -403.368002)
				)
			)
		)
	)
)
